# T6G (Grand Teton) — schematic netlist excerpt (pin names and nets, part order shuffled) for the footprints in the layout excerpt that follows; sources: Cadence DE-HDL packaged netlist, KiCad conversion of 04192023_DAF0TMB3IC0_F0TG_MB_C_brd_V02_OCP.brd

R872  Q_RES  0 5% CHIP  pkg 0201LF  page 342 : A = SMB_RT_CPU1_P2_R_SCL ; B = SMB_RT_CPU1_P2_R2_SCL
C510  Q_CAP  4.7UF 6.3V 20% X6S  pkg 0402  page 279 : A = P1V8_CPU0_RT0_1A ; B = GND
R1290  Q_RES  22 1% EMPTY  pkg 0402LF  page 132 : A = OCP_SFF_RBT_ARB_IN_R ; B = OCP_SFF_RBT_ARB_IN

(kicad_pcb
	(version 20260206)
	(generator "pcbnew")
	(generator_version "10.0")
	(general
		(thickness 1.6)
		(legacy_teardrops no)
	)
	(paper "A4")
	(title_block
		(title "04192023_DAF0TMB3IC0_F0TG_MB_C_brd_V02_OCP.brd")
		(comment 1 "Grand Teton / footprints 6256-6258 of 8354")
	)
	(layers
		(0 "F.Cu" signal "TOP")
		(4 "In1.Cu" signal "GND")
		(6 "In2.Cu" signal "IN1")
		(8 "In3.Cu" signal "GND1")
		(10 "In4.Cu" signal "IN2")
		(12 "In5.Cu" signal "GND2")
		(14 "In6.Cu" signal "IN3")
		(16 "In7.Cu" signal "GND3")
		(18 "In8.Cu" signal "VCC")
		(20 "In9.Cu" signal "VCC1")
		(22 "In10.Cu" signal "GND4")
		(24 "In11.Cu" signal "IN4")
		(26 "In12.Cu" signal "GND5")
		(28 "In13.Cu" signal "IN5")
		(30 "In14.Cu" signal "GND6")
		(32 "In15.Cu" signal "IN6")
		(34 "In16.Cu" signal "GND7")
		(2 "B.Cu" signal "BOTTOM")
		(9 "F.Adhes" user "F.Adhesive")
		(11 "B.Adhes" user "B.Adhesive")
		(13 "F.Paste" user "Package Geometry/Pastemask Top")
		(15 "B.Paste" user "Package Geometry/Pastemask Bottom")
		(5 "F.SilkS" user "Ref Des/Silkscreen Top")
		(7 "B.SilkS" user "Ref Des/Silkscreen Bottom")
		(1 "F.Mask" user "Board Geometry/Soldermask Top")
		(3 "B.Mask" user "Board Geometry/Soldermask Bottom")
		(17 "Dwgs.User" user "User.Drawings")
		(19 "Cmts.User" user "User.Comments")
		(21 "Eco1.User" user "User.Eco1")
		(23 "Eco2.User" user "User.Eco2")
		(25 "Edge.Cuts" user "Board Geometry/Outline")
		(27 "Margin" user)
		(31 "F.CrtYd" user "Package Geometry/Place Bound Top")
		(29 "B.CrtYd" user "Package Geometry/Place Bound Bottom")
		(35 "F.Fab" user "Ref Des/Assembly Top")
		(33 "B.Fab" user "Ref Des/Assembly Bottom")
	)
	(footprint ""
		(layer "B.Cu")
		(at 191.271144 -79.05623 -90)
		(property "Reference" "R1290"
			(at 0 0 90)
			(layer "B.SilkS")
			(hide yes)
			(effects
				(font
					(size 1.27 1.27)
				)
				(justify mirror)
			)
		)
		(property "Value" ""
			(at 0 0 90)
			(layer "B.Fab")
			(effects
				(font
					(size 1.27 1.27)
				)
				(justify mirror)
			)
		)
		(duplicate_pad_numbers_are_jumpers no)
		(fp_line
			(start -0.7874 0.4064)
			(end 0.7874 0.4064)
			(stroke
				(width 0.1524)
				(type default)
			)
			(layer "B.SilkS")
		)
		(fp_line
			(start 0.7874 0.4064)
			(end 0.7874 -0.4064)
			(stroke
				(width 0.1524)
				(type default)
			)
			(layer "B.SilkS")
		)
		(fp_line
			(start -0.7874 -0.4064)
			(end -0.7874 0.4064)
			(stroke
				(width 0.1524)
				(type default)
			)
			(layer "B.SilkS")
		)
		(fp_line
			(start 0.7874 -0.4064)
			(end -0.7874 -0.4064)
			(stroke
				(width 0.1524)
				(type default)
			)
			(layer "B.SilkS")
		)
		(fp_line
			(start -0.67945 0.3048)
			(end -0.120396 0.3048)
			(stroke
				(width 0.1)
				(type default)
			)
			(layer "B.Fab")
		)
		(fp_line
			(start -0.120396 0.3048)
			(end -0.120396 0.2794)
			(stroke
				(width 0.1)
				(type default)
			)
			(layer "B.Fab")
		)
		(fp_line
			(start 0.12065 0.3048)
			(end 0.67945 0.3048)
			(stroke
				(width 0.1)
				(type default)
			)
			(layer "B.Fab")
		)
		(fp_line
			(start 0.67945 0.3048)
			(end 0.67945 -0.305054)
			(stroke
				(width 0.1)
				(type default)
			)
			(layer "B.Fab")
		)
		(fp_line
			(start -0.120396 0.2794)
			(end 0.12065 0.2794)
			(stroke
				(width 0.1)
				(type default)
			)
			(layer "B.Fab")
		)
		(fp_line
			(start 0.12065 0.2794)
			(end 0.12065 0.3048)
			(stroke
				(width 0.1)
				(type default)
			)
			(layer "B.Fab")
		)
		(fp_line
			(start -0.12065 -0.2794)
			(end -0.12065 -0.3048)
			(stroke
				(width 0.1)
				(type default)
			)
			(layer "B.Fab")
		)
		(fp_line
			(start 0.12065 -0.2794)
			(end -0.12065 -0.2794)
			(stroke
				(width 0.1)
				(type default)
			)
			(layer "B.Fab")
		)
		(fp_line
			(start -0.67945 -0.3048)
			(end -0.67945 0.3048)
			(stroke
				(width 0.1)
				(type default)
			)
			(layer "B.Fab")
		)
		(fp_line
			(start -0.12065 -0.3048)
			(end -0.67945 -0.3048)
			(stroke
				(width 0.1)
				(type default)
			)
			(layer "B.Fab")
		)
		(fp_line
			(start 0.12065 -0.305054)
			(end 0.12065 -0.2794)
			(stroke
				(width 0.1)
				(type default)
			)
			(layer "B.Fab")
		)
		(fp_line
			(start 0.67945 -0.305054)
			(end 0.12065 -0.305054)
			(stroke
				(width 0.1)
				(type default)
			)
			(layer "B.Fab")
		)
		(pad "1" smd circle
			(at 0.40005 0 90)
			(size 0 0)
			(layers "B.Cu" "B.Mask" "B.Paste")
			(net "OCP_SFF_RBT_ARB_IN_R")
		)
		(pad "2" smd circle
			(at -0.40005 0 90)
			(size 0 0)
			(layers "B.Cu" "B.Mask" "B.Paste")
			(net "OCP_SFF_RBT_ARB_IN")
		)
	)
	(footprint ""
		(layer "B.Cu")
		(at 215.0618 -341.884)
		(property "Reference" "R872"
			(at 0 0 0)
			(layer "B.SilkS")
			(hide yes)
			(effects
				(font
					(size 1.27 1.27)
				)
				(justify mirror)
			)
		)
		(property "Value" ""
			(at 0 0 0)
			(layer "B.Fab")
			(effects
				(font
					(size 1.27 1.27)
				)
				(justify mirror)
			)
		)
		(duplicate_pad_numbers_are_jumpers no)
		(fp_line
			(start -0.32512 -0.175006)
			(end -0.32512 0.175006)
			(stroke
				(width 0.1)
				(type default)
			)
			(layer "B.Fab")
		)
		(fp_line
			(start -0.32512 0.175006)
			(end 0.32512 0.175006)
			(stroke
				(width 0.1)
				(type default)
			)
			(layer "B.Fab")
		)
		(fp_line
			(start 0.32512 -0.175006)
			(end -0.32512 -0.175006)
			(stroke
				(width 0.1)
				(type default)
			)
			(layer "B.Fab")
		)
		(fp_line
			(start 0.32512 0.175006)
			(end 0.32512 -0.175006)
			(stroke
				(width 0.1)
				(type default)
			)
			(layer "B.Fab")
		)
		(pad "1" smd rect
			(at 0.2667 0 180)
			(size 0.3048 0.381)
			(layers "B.Cu" "B.Mask" "B.Paste")
			(net "SMB_RT_CPU1_P2_R_SCL")
		)
		(pad "2" smd rect
			(at -0.2667 0)
			(size 0.3048 0.381)
			(layers "B.Cu" "B.Mask" "B.Paste")
			(net "SMB_RT_CPU1_P2_R2_SCL")
		)
	)
	(footprint ""
		(layer "B.Cu")
		(at 311.791096 -398.942052 90)
		(property "Reference" "C510"
			(at 0 0 90)
			(layer "B.SilkS")
			(hide yes)
			(effects
				(font
					(size 1.27 1.27)
				)
				(justify mirror)
			)
		)
		(property "Value" ""
			(at 0 0 90)
			(layer "B.Fab")
			(effects
				(font
					(size 1.27 1.27)
				)
				(justify mirror)
			)
		)
		(duplicate_pad_numbers_are_jumpers no)
		(fp_line
			(start 0.7874 -0.4064)
			(end -0.7874 -0.4064)
			(stroke
				(width 0.1524)
				(type default)
			)
			(layer "B.SilkS")
		)
		(fp_line
			(start -0.7874 -0.4064)
			(end -0.7874 0.4064)
			(stroke
				(width 0.1524)
				(type default)
			)
			(layer "B.SilkS")
		)
		(fp_line
			(start 0.7874 0.4064)
			(end 0.7874 -0.4064)
			(stroke
				(width 0.1524)
				(type default)
			)
			(layer "B.SilkS")
		)
		(fp_line
			(start -0.7874 0.4064)
			(end 0.7874 0.4064)
			(stroke
				(width 0.1524)
				(type default)
			)
			(layer "B.SilkS")
		)
		(fp_line
			(start 0.67945 -0.305054)
			(end 0.12065 -0.305054)
			(stroke
				(width 0.1)
				(type default)
			)
			(layer "B.Fab")
		)
		(fp_line
			(start 0.12065 -0.305054)
			(end 0.12065 -0.2794)
			(stroke
				(width 0.1)
				(type default)
			)
			(layer "B.Fab")
		)
		(fp_line
			(start -0.12065 -0.3048)
			(end -0.67945 -0.3048)
			(stroke
				(width 0.1)
				(type default)
			)
			(layer "B.Fab")
		)
		(fp_line
			(start -0.67945 -0.3048)
			(end -0.67945 0.3048)
			(stroke
				(width 0.1)
				(type default)
			)
			(layer "B.Fab")
		)
		(fp_line
			(start 0.12065 -0.2794)
			(end -0.12065 -0.2794)
			(stroke
				(width 0.1)
				(type default)
			)
			(layer "B.Fab")
		)
		(fp_line
			(start -0.12065 -0.2794)
			(end -0.12065 -0.3048)
			(stroke
				(width 0.1)
				(type default)
			)
			(layer "B.Fab")
		)
		(fp_line
			(start 0.12065 0.2794)
			(end 0.12065 0.3048)
			(stroke
				(width 0.1)
				(type default)
			)
			(layer "B.Fab")
		)
		(fp_line
			(start -0.120396 0.2794)
			(end 0.12065 0.2794)
			(stroke
				(width 0.1)
				(type default)
			)
			(layer "B.Fab")
		)
		(fp_line
			(start 0.67945 0.3048)
			(end 0.67945 -0.305054)
			(stroke
				(width 0.1)
				(type default)
			)
			(layer "B.Fab")
		)
		(fp_line
			(start 0.12065 0.3048)
			(end 0.67945 0.3048)
			(stroke
				(width 0.1)
				(type default)
			)
			(layer "B.Fab")
		)
		(fp_line
			(start -0.120396 0.3048)
			(end -0.120396 0.2794)
			(stroke
				(width 0.1)
				(type default)
			)
			(layer "B.Fab")
		)
		(fp_line
			(start -0.67945 0.3048)
			(end -0.120396 0.3048)
			(stroke
				(width 0.1)
				(type default)
			)
			(layer "B.Fab")
		)
		(pad "1" smd circle
			(at 0.40005 0 270)
			(size 0 0)
			(layers "B.Cu" "B.Mask" "B.Paste")
			(net "P1V8_CPU0_RT0_1A")
		)
		(pad "2" smd circle
			(at -0.40005 0 270)
			(size 0 0)
			(layers "B.Cu" "B.Mask" "B.Paste")
			(net "GND")
		)
	)
)
